# TIMECARD (Time Appliance Project (Time Card)) — schematic netlist excerpt (pin names and nets, part order shuffled) for the footprints in the layout excerpt that follows; sources: Cadence DE-HDL packaged netlist, KiCad conversion of R4006-B0001-02_R01.brd

SP69  NULL  pkg DUMMY  page 34
C32  CAPACITOR  10UF 25V 20%  pkg SMC_0805R_H057  page 32 : \1\ = VIN_XP5R0V ; \2\ = SG
R84  RESISTOR  0OHM -  pkg SMC_0402R_H016  page 21 : \1\ = FPGA_OUT_MAC_PPS_IN1N ; \2\ = R_MAC_PPS_IN1N

(kicad_pcb
	(version 20260206)
	(generator "pcbnew")
	(generator_version "10.0")
	(general
		(thickness 1.6)
		(legacy_teardrops no)
	)
	(paper "A4")
	(title_block
		(title "timecard-production-celestica-r4006 — R4006-B0001-02_R01.brd")
		(comment 1 "Time Appliance Project (Time Card) / footprints 147-149 of 1113")
	)
	(layers
		(0 "F.Cu" signal "TOP")
		(4 "In1.Cu" signal "L02_GND1")
		(6 "In2.Cu" signal "L03_SIG1")
		(8 "In3.Cu" signal "L04_GND2")
		(10 "In4.Cu" signal "L05_VCC1")
		(12 "In5.Cu" signal "L06_VCC2")
		(14 "In6.Cu" signal "L07_GND3")
		(16 "In7.Cu" signal "L08_SIG2")
		(18 "In8.Cu" signal "L09_GND4")
		(2 "B.Cu" signal "BOTTOM")
		(9 "F.Adhes" user "F.Adhesive")
		(11 "B.Adhes" user "B.Adhesive")
		(13 "F.Paste" user "Package Geometry/Pastemask Top")
		(15 "B.Paste" user "Package Geometry/Pastemask Bottom")
		(5 "F.SilkS" user "Ref Des/Silkscreen Top")
		(7 "B.SilkS" user "Ref Des/Silkscreen Bottom")
		(1 "F.Mask" user "Board Geometry/Soldermask Top")
		(3 "B.Mask" user "Board Geometry/Soldermask Bottom")
		(17 "Dwgs.User" user "User.Drawings")
		(19 "Cmts.User" user "User.Comments")
		(21 "Eco1.User" user "User.Eco1")
		(23 "Eco2.User" user "User.Eco2")
		(25 "Edge.Cuts" user "Board Geometry/Outline")
		(27 "Margin" user)
		(31 "F.CrtYd" user "Package Geometry/Place Bound Top")
		(29 "B.CrtYd" user "Package Geometry/Place Bound Bottom")
		(35 "F.Fab" user "Ref Des/Assembly Top")
		(33 "B.Fab" user "Ref Des/Assembly Bottom")
	)
	(footprint ""
		(layer "F.Cu")
		(at 43.4594 -95.9104)
		(property "Reference" "C32"
			(at 0.127 4.05257 0)
			(unlocked yes)
			(layer "F.SilkS")
			(effects
				(font
					(size 0.7874 0.5842)
					(thickness 0.1524)
				)
			)
		)
		(property "Value" "VAL*"
			(at 0.0762 3.134106 0)
			(unlocked yes)
			(layer "F.Fab")
			(hide yes)
			(effects
				(font
					(size 0.7874 0.5842)
					(thickness 0.1524)
				)
			)
		)
		(property "Device Type" "CAPACITOR-G107-0F106-EM,10UF,2A"
			(at 0.0508 2.194306 0)
			(unlocked yes)
			(layer "F.Fab")
			(hide yes)
			(effects
				(font
					(size 0.7874 0.5842)
					(thickness 0.1524)
				)
			)
		)
		(property "User Part Number" "PARTNUM*"
			(at 0.1016 5.013706 0)
			(unlocked yes)
			(layer "Cmts.User")
			(hide yes)
			(effects
				(font
					(size 0.7874 0.5842)
					(thickness 0.1524)
				)
			)
		)
		(property "Tolerance" "TOL*"
			(at 0.0762 4.048506 0)
			(unlocked yes)
			(layer "Cmts.User")
			(hide yes)
			(effects
				(font
					(size 0.7874 0.5842)
					(thickness 0.1524)
				)
			)
		)
		(duplicate_pad_numbers_are_jumpers no)
		(fp_line
			(start -1.5748 -0.9398)
			(end -1.5748 0.9398)
			(stroke
				(width 0.1)
				(type default)
			)
			(layer "F.SilkS")
		)
		(fp_line
			(start -1.5748 0.9398)
			(end 1.5748 0.9398)
			(stroke
				(width 0.1)
				(type default)
			)
			(layer "F.SilkS")
		)
		(fp_line
			(start 1.5748 -0.9398)
			(end -1.5748 -0.9398)
			(stroke
				(width 0.1)
				(type default)
			)
			(layer "F.SilkS")
		)
		(fp_line
			(start 1.5748 0.9398)
			(end 1.5748 -0.9398)
			(stroke
				(width 0.1)
				(type default)
			)
			(layer "F.SilkS")
		)
		(fp_rect
			(start 1.5748 -0.9398)
			(end -1.5748 0.9398)
			(stroke
				(width 0)
				(type default)
			)
			(fill no)
			(layer "F.CrtYd")
		)
		(fp_line
			(start -1.016 -0.635)
			(end -1.016 0.635)
			(stroke
				(width 0.1)
				(type default)
			)
			(layer "F.Fab")
		)
		(fp_line
			(start -1.016 0.635)
			(end 1.016 0.635)
			(stroke
				(width 0.1)
				(type default)
			)
			(layer "F.Fab")
		)
		(fp_line
			(start 1.016 -0.635)
			(end -1.016 -0.635)
			(stroke
				(width 0.1)
				(type default)
			)
			(layer "F.Fab")
		)
		(fp_line
			(start 1.016 0.635)
			(end 1.016 -0.635)
			(stroke
				(width 0.1)
				(type default)
			)
			(layer "F.Fab")
		)
		(pad "1" smd rect
			(at -0.8382 0)
			(size 0.9652 1.3716)
			(layers "F.Cu" "F.Mask" "F.Paste")
			(net "VIN_XP5R0V")
		)
		(pad "2" smd rect
			(at 0.8382 0)
			(size 0.9652 1.3716)
			(layers "F.Cu" "F.Mask" "F.Paste")
			(net "SG")
		)
		(zone
			(layer "F.Cu")
			(hatch none 0.5)
			(connect_pads
				(clearance 0)
			)
			(min_thickness 0.25)
			(keepout
				(tracks allowed)
				(vias not_allowed)
				(pads allowed)
				(copperpour not_allowed)
				(footprints allowed)
			)
			(placement
				(enabled no)
				(sheetname "")
			)
			(fill
				(thermal_gap 0.5)
				(thermal_bridge_width 0.5)
				(island_removal_mode 0)
			)
			(polygon
				(pts
					(xy 43.688 -96.5454) (xy 43.2308 -96.5454) (xy 43.2308 -95.2754) (xy 43.688 -95.2754)
				)
			)
		)
	)
	(footprint ""
		(layer "F.Cu")
		(at 51.054 -126.111)
		(property "Reference" "SP69"
			(at 0 0 0)
			(layer "F.SilkS")
			(hide yes)
			(effects
				(font
					(size 1.27 1.27)
				)
			)
		)
		(property "Value" ""
			(at 0 0 0)
			(layer "F.Fab")
			(effects
				(font
					(size 1.27 1.27)
				)
			)
		)
		(duplicate_pad_numbers_are_jumpers no)
	)
	(footprint ""
		(layer "F.Cu")
		(at 81.0006 -52.324 180)
		(property "Reference" "R84"
			(at 0.9906 -14.39037 0)
			(unlocked yes)
			(layer "F.SilkS")
			(effects
				(font
					(size 0.7874 0.5842)
					(thickness 0.1524)
				)
			)
		)
		(property "Value" "VAL*"
			(at 0.02032 2.13233 180)
			(unlocked yes)
			(layer "F.Fab")
			(hide yes)
			(effects
				(font
					(size 0.7874 0.5842)
					(thickness 0.1524)
				)
			)
		)
		(property "Tolerance" "TOL*"
			(at 0.044704 3.05435 180)
			(unlocked yes)
			(layer "Cmts.User")
			(hide yes)
			(effects
				(font
					(size 0.7874 0.5842)
					(thickness 0.1524)
				)
			)
		)
		(property "User Part Number" "PARTNUM*"
			(at 0.02032 4.024884 180)
			(unlocked yes)
			(layer "Cmts.User")
			(hide yes)
			(effects
				(font
					(size 0.7874 0.5842)
					(thickness 0.1524)
				)
			)
		)
		(property "Device Type" "RESISTOR-G155-100R0-J0,0OHM,-"
			(at 0.008382 1.210564 180)
			(unlocked yes)
			(layer "F.Fab")
			(hide yes)
			(effects
				(font
					(size 0.7874 0.5842)
					(thickness 0.1524)
				)
			)
		)
		(duplicate_pad_numbers_are_jumpers no)
		(fp_line
			(start 1.143 0.5588)
			(end 1.143 -0.5588)
			(stroke
				(width 0.1)
				(type default)
			)
			(layer "F.SilkS")
		)
		(fp_line
			(start 1.143 -0.5588)
			(end -1.143 -0.5588)
			(stroke
				(width 0.1)
				(type default)
			)
			(layer "F.SilkS")
		)
		(fp_line
			(start -1.143 0.5588)
			(end 1.143 0.5588)
			(stroke
				(width 0.1)
				(type default)
			)
			(layer "F.SilkS")
		)
		(fp_line
			(start -1.143 -0.5588)
			(end -1.143 0.5588)
			(stroke
				(width 0.1)
				(type default)
			)
			(layer "F.SilkS")
		)
		(fp_rect
			(start 1.143 -0.5588)
			(end -1.143 0.5588)
			(stroke
				(width 0)
				(type default)
			)
			(fill no)
			(layer "F.CrtYd")
		)
		(fp_line
			(start 0.508 0.3048)
			(end 0.508 -0.3048)
			(stroke
				(width 0.1)
				(type default)
			)
			(layer "F.Fab")
		)
		(fp_line
			(start 0.508 -0.3048)
			(end -0.508 -0.3048)
			(stroke
				(width 0.1)
				(type default)
			)
			(layer "F.Fab")
		)
		(fp_line
			(start -0.508 0.3048)
			(end 0.508 0.3048)
			(stroke
				(width 0.1)
				(type default)
			)
			(layer "F.Fab")
		)
		(fp_line
			(start -0.508 -0.3048)
			(end -0.508 0.3048)
			(stroke
				(width 0.1)
				(type default)
			)
			(layer "F.Fab")
		)
		(pad "1" smd rect
			(at -0.5334 0 180)
			(size 0.7112 0.6096)
			(layers "F.Cu" "F.Mask" "F.Paste")
			(net "FPGA_OUT_MAC_PPS_IN1N")
		)
		(pad "2" smd rect
			(at 0.5334 0 180)
			(size 0.7112 0.6096)
			(layers "F.Cu" "F.Mask" "F.Paste")
			(net "R_MAC_PPS_IN1N")
		)
		(zone
			(layer "F.Cu")
			(hatch none 0.5)
			(connect_pads
				(clearance 0)
			)
			(min_thickness 0.25)
			(keepout
				(tracks allowed)
				(vias not_allowed)
				(pads allowed)
				(copperpour not_allowed)
				(footprints allowed)
			)
			(placement
				(enabled no)
				(sheetname "")
			)
			(fill
				(thermal_gap 0.5)
				(thermal_bridge_width 0.5)
				(island_removal_mode 0)
			)
			(polygon
				(pts
					(xy 80.9244 -52.0192) (xy 81.0768 -52.0192) (xy 81.0768 -52.6288) (xy 80.9244 -52.6288)
				)
			)
		)
	)
)
